# T6G (Grand Teton) — schematic netlist excerpt (pin names and nets, part order shuffled) for the footprints in the layout excerpt that follows; sources: Cadence DE-HDL packaged netlist, KiCad conversion of 04192023_DAF0TMB3IC0_F0TG_MB_C_brd_V02_OCP.brd

R4090  Q_RES  1K 1% CHIP  pkg 0402LF  page 237 : A = P3V3_AUX ; B = M2_0_P3V3_ADC_ALERT_R
R6204  Q_RES  10K 1% CHIP  pkg 0402LF  page 176 : A = P3V3_AUX ; B = PU_CPU0_USB_HUB_PWR_EN

(kicad_pcb
	(version 20260206)
	(generator "pcbnew")
	(generator_version "10.0")
	(general
		(thickness 1.6)
		(legacy_teardrops no)
	)
	(paper "A4")
	(title_block
		(title "04192023_DAF0TMB3IC0_F0TG_MB_C_brd_V02_OCP.brd")
		(comment 1 "Grand Teton / footprints 3858-3859 of 8354")
	)
	(layers
		(0 "F.Cu" signal "TOP")
		(4 "In1.Cu" signal "GND")
		(6 "In2.Cu" signal "IN1")
		(8 "In3.Cu" signal "GND1")
		(10 "In4.Cu" signal "IN2")
		(12 "In5.Cu" signal "GND2")
		(14 "In6.Cu" signal "IN3")
		(16 "In7.Cu" signal "GND3")
		(18 "In8.Cu" signal "VCC")
		(20 "In9.Cu" signal "VCC1")
		(22 "In10.Cu" signal "GND4")
		(24 "In11.Cu" signal "IN4")
		(26 "In12.Cu" signal "GND5")
		(28 "In13.Cu" signal "IN5")
		(30 "In14.Cu" signal "GND6")
		(32 "In15.Cu" signal "IN6")
		(34 "In16.Cu" signal "GND7")
		(2 "B.Cu" signal "BOTTOM")
		(9 "F.Adhes" user "F.Adhesive")
		(11 "B.Adhes" user "B.Adhesive")
		(13 "F.Paste" user "Package Geometry/Pastemask Top")
		(15 "B.Paste" user "Package Geometry/Pastemask Bottom")
		(5 "F.SilkS" user "Ref Des/Silkscreen Top")
		(7 "B.SilkS" user "Ref Des/Silkscreen Bottom")
		(1 "F.Mask" user "Board Geometry/Soldermask Top")
		(3 "B.Mask" user "Board Geometry/Soldermask Bottom")
		(17 "Dwgs.User" user "User.Drawings")
		(19 "Cmts.User" user "User.Comments")
		(21 "Eco1.User" user "User.Eco1")
		(23 "Eco2.User" user "User.Eco2")
		(25 "Edge.Cuts" user "Board Geometry/Outline")
		(27 "Margin" user)
		(31 "F.CrtYd" user "Package Geometry/Place Bound Top")
		(29 "B.CrtYd" user "Package Geometry/Place Bound Bottom")
		(35 "F.Fab" user "Ref Des/Assembly Top")
		(33 "B.Fab" user "Ref Des/Assembly Bottom")
	)
	(footprint ""
		(layer "F.Cu")
		(at 150.500842 -53.083714)
		(property "Reference" "R4090"
			(at 0 0 0)
			(layer "F.SilkS")
			(hide yes)
			(effects
				(font
					(size 1.27 1.27)
				)
			)
		)
		(property "Value" ""
			(at 0 0 0)
			(layer "F.Fab")
			(effects
				(font
					(size 1.27 1.27)
				)
			)
		)
		(duplicate_pad_numbers_are_jumpers no)
		(fp_line
			(start -0.7874 -0.4064)
			(end 0.7874 -0.4064)
			(stroke
				(width 0.1524)
				(type default)
			)
			(layer "F.SilkS")
		)
		(fp_line
			(start -0.7874 0.4064)
			(end -0.7874 -0.4064)
			(stroke
				(width 0.1524)
				(type default)
			)
			(layer "F.SilkS")
		)
		(fp_line
			(start 0.7874 -0.4064)
			(end 0.7874 0.4064)
			(stroke
				(width 0.1524)
				(type default)
			)
			(layer "F.SilkS")
		)
		(fp_line
			(start 0.7874 0.4064)
			(end -0.7874 0.4064)
			(stroke
				(width 0.1524)
				(type default)
			)
			(layer "F.SilkS")
		)
		(fp_line
			(start -0.67945 -0.305054)
			(end -0.12065 -0.305054)
			(stroke
				(width 0.1)
				(type default)
			)
			(layer "F.Fab")
		)
		(fp_line
			(start -0.67945 0.3048)
			(end -0.67945 -0.305054)
			(stroke
				(width 0.1)
				(type default)
			)
			(layer "F.Fab")
		)
		(fp_line
			(start -0.12065 -0.305054)
			(end -0.12065 -0.2794)
			(stroke
				(width 0.1)
				(type default)
			)
			(layer "F.Fab")
		)
		(fp_line
			(start -0.12065 -0.2794)
			(end 0.12065 -0.2794)
			(stroke
				(width 0.1)
				(type default)
			)
			(layer "F.Fab")
		)
		(fp_line
			(start -0.12065 0.2794)
			(end -0.12065 0.3048)
			(stroke
				(width 0.1)
				(type default)
			)
			(layer "F.Fab")
		)
		(fp_line
			(start -0.12065 0.3048)
			(end -0.67945 0.3048)
			(stroke
				(width 0.1)
				(type default)
			)
			(layer "F.Fab")
		)
		(fp_line
			(start 0.120396 0.2794)
			(end -0.12065 0.2794)
			(stroke
				(width 0.1)
				(type default)
			)
			(layer "F.Fab")
		)
		(fp_line
			(start 0.120396 0.3048)
			(end 0.120396 0.2794)
			(stroke
				(width 0.1)
				(type default)
			)
			(layer "F.Fab")
		)
		(fp_line
			(start 0.12065 -0.3048)
			(end 0.67945 -0.3048)
			(stroke
				(width 0.1)
				(type default)
			)
			(layer "F.Fab")
		)
		(fp_line
			(start 0.12065 -0.2794)
			(end 0.12065 -0.3048)
			(stroke
				(width 0.1)
				(type default)
			)
			(layer "F.Fab")
		)
		(fp_line
			(start 0.67945 -0.3048)
			(end 0.67945 0.3048)
			(stroke
				(width 0.1)
				(type default)
			)
			(layer "F.Fab")
		)
		(fp_line
			(start 0.67945 0.3048)
			(end 0.120396 0.3048)
			(stroke
				(width 0.1)
				(type default)
			)
			(layer "F.Fab")
		)
		(pad "1" smd circle
			(at -0.40005 0)
			(size 0 0)
			(layers "F.Cu" "F.Mask" "F.Paste")
			(net "P3V3_AUX")
		)
		(pad "2" smd circle
			(at 0.40005 0)
			(size 0 0)
			(layers "F.Cu" "F.Mask" "F.Paste")
			(net "M2_0_P3V3_ADC_ALERT_R")
		)
	)
	(footprint ""
		(layer "F.Cu")
		(at 128.906778 -47.121064)
		(property "Reference" "R6204"
			(at 0 0 0)
			(layer "F.SilkS")
			(hide yes)
			(effects
				(font
					(size 1.27 1.27)
				)
			)
		)
		(property "Value" ""
			(at 0 0 0)
			(layer "F.Fab")
			(effects
				(font
					(size 1.27 1.27)
				)
			)
		)
		(duplicate_pad_numbers_are_jumpers no)
		(fp_line
			(start -0.7874 -0.4064)
			(end 0.7874 -0.4064)
			(stroke
				(width 0.1524)
				(type default)
			)
			(layer "F.SilkS")
		)
		(fp_line
			(start -0.7874 0.4064)
			(end -0.7874 -0.4064)
			(stroke
				(width 0.1524)
				(type default)
			)
			(layer "F.SilkS")
		)
		(fp_line
			(start 0.7874 -0.4064)
			(end 0.7874 0.4064)
			(stroke
				(width 0.1524)
				(type default)
			)
			(layer "F.SilkS")
		)
		(fp_line
			(start 0.7874 0.4064)
			(end -0.7874 0.4064)
			(stroke
				(width 0.1524)
				(type default)
			)
			(layer "F.SilkS")
		)
		(fp_line
			(start -0.67945 -0.305054)
			(end -0.12065 -0.305054)
			(stroke
				(width 0.1)
				(type default)
			)
			(layer "F.Fab")
		)
		(fp_line
			(start -0.67945 0.3048)
			(end -0.67945 -0.305054)
			(stroke
				(width 0.1)
				(type default)
			)
			(layer "F.Fab")
		)
		(fp_line
			(start -0.12065 -0.305054)
			(end -0.12065 -0.2794)
			(stroke
				(width 0.1)
				(type default)
			)
			(layer "F.Fab")
		)
		(fp_line
			(start -0.12065 -0.2794)
			(end 0.12065 -0.2794)
			(stroke
				(width 0.1)
				(type default)
			)
			(layer "F.Fab")
		)
		(fp_line
			(start -0.12065 0.2794)
			(end -0.12065 0.3048)
			(stroke
				(width 0.1)
				(type default)
			)
			(layer "F.Fab")
		)
		(fp_line
			(start -0.12065 0.3048)
			(end -0.67945 0.3048)
			(stroke
				(width 0.1)
				(type default)
			)
			(layer "F.Fab")
		)
		(fp_line
			(start 0.120396 0.2794)
			(end -0.12065 0.2794)
			(stroke
				(width 0.1)
				(type default)
			)
			(layer "F.Fab")
		)
		(fp_line
			(start 0.120396 0.3048)
			(end 0.120396 0.2794)
			(stroke
				(width 0.1)
				(type default)
			)
			(layer "F.Fab")
		)
		(fp_line
			(start 0.12065 -0.3048)
			(end 0.67945 -0.3048)
			(stroke
				(width 0.1)
				(type default)
			)
			(layer "F.Fab")
		)
		(fp_line
			(start 0.12065 -0.2794)
			(end 0.12065 -0.3048)
			(stroke
				(width 0.1)
				(type default)
			)
			(layer "F.Fab")
		)
		(fp_line
			(start 0.67945 -0.3048)
			(end 0.67945 0.3048)
			(stroke
				(width 0.1)
				(type default)
			)
			(layer "F.Fab")
		)
		(fp_line
			(start 0.67945 0.3048)
			(end 0.120396 0.3048)
			(stroke
				(width 0.1)
				(type default)
			)
			(layer "F.Fab")
		)
		(pad "1" smd circle
			(at -0.40005 0)
			(size 0 0)
			(layers "F.Cu" "F.Mask" "F.Paste")
			(net "P3V3_AUX")
		)
		(pad "2" smd circle
			(at 0.40005 0)
			(size 0 0)
			(layers "F.Cu" "F.Mask" "F.Paste")
			(net "PU_CPU0_USB_HUB_PWR_EN")
		)
	)
)
